# T6G (Grand Teton) — schematic netlist excerpt (pin names and nets, part order shuffled) for the footprints in the layout excerpt that follows; sources: Cadence DE-HDL packaged netlist, KiCad conversion of 04192023_DAF0TMB3IC0_F0TG_MB_C_brd_V02_OCP.brd

J29  SCONN288_DDR506112002KQ  IO  pkg DDR288S_1-1VXC  page 107
  VIN_BULK0  = P12V_MEM_CPU1
  RFU0  = NC
  VIN_MGMT  = P3V3_AUX
  HSCL  = I3C_SPD_DDRJ_CPU1_SCL
  HSDA  = I3C_SPD_DDRJ_CPU1_SDA
  VSS0  = GND
  DQ0_A  = M_J_CPU1_SA_DQ<0>
  VSS1  = GND
  DQ1_A  = M_J_CPU1_SA_DQ<1>
  VSS2  = GND
  DQS0_A_T  = M_J_CPU1_SA_DQS_DP<0>
  DQS0_A_C  = M_J_CPU1_SA_DQS_DN<0>
  VSS3  = GND
  DQ4_A  = M_J_CPU1_SA_DQ<4>
  VSS4  = GND
  DQ5_A  = M_J_CPU1_SA_DQ<5>
  VSS5  = GND
  DQ8_A  = M_J_CPU1_SA_DQ<8>
  VSS6  = GND
  DQ9_A  = M_J_CPU1_SA_DQ<9>
  VSS7  = GND
  DQS1_A_T  = M_J_CPU1_SA_DQS_DP<1>
  DQS1_A_C  = M_J_CPU1_SA_DQS_DN<1>
  VSS8  = GND
  DQ12_A  = M_J_CPU1_SA_DQ<12>
  VSS9  = GND
  DQ13_A  = M_J_CPU1_SA_DQ<13>
  VSS10  = GND
  DQ16_A  = M_J_CPU1_SA_DQ<16>
  VSS11  = GND
  DQ17_A  = M_J_CPU1_SA_DQ<17>
  VSS12  = GND
  DQS2_A_T  = M_J_CPU1_SA_DQS_DP<2>
  DQS2_A_C  = M_J_CPU1_SA_DQS_DN<2>
  VSS13  = GND
  DQ20_A  = M_J_CPU1_SA_DQ<20>
  VSS14  = GND
  DQ21_A  = M_J_CPU1_SA_DQ<21>
  VSS15  = GND
  DQ24_A  = M_J_CPU1_SA_DQ<24>
  VSS16  = GND
  DQ25_A  = M_J_CPU1_SA_DQ<25>
  VSS17  = GND
  DQS3_A_T  = M_J_CPU1_SA_DQS_DP<3>
  DQS3_A_C  = M_J_CPU1_SA_DQS_DN<3>
  VSS18  = GND
  DQ28_A  = M_J_CPU1_SA_DQ<28>
  VSS19  = GND
  DQ29_A  = M_J_CPU1_SA_DQ<29>
  VSS20  = GND
  CB0_A  = M_J_CPU1_SA_CB<0>
  VSS21  = GND
  CB1_A  = M_J_CPU1_SA_CB<1>
  VSS22  = GND
  DQS4_A_T  = M_J_CPU1_SA_DQS_DP<4>
  DQS4_A_C  = M_J_CPU1_SA_DQS_DN<4>
  VSS23  = GND
  CB4_A  = M_J_CPU1_SA_CB<4>
  VSS24  = GND
  CB5_A  = M_J_CPU1_SA_CB<5>
  VSS25  = GND
  ALERT_N  = M_J_CPU1_ALERT_N
  VSS26  = GND
  CS0_A_N  = M_J_CPU1_SA_CS_N<0>
  VSS27  = GND
  CA0_A  = M_J_CPU1_SA_CA<0>
  VSS28  = GND
  CA2_A  = M_J_CPU1_SA_CA<2>
  VSS29  = GND
  CA4_A  = M_J_CPU1_SA_CA<4>
  VSS30  = GND
  CA6_A  = M_J_CPU1_SA_CA<6>
  VSS31  = GND
  PAR_A  = M_J_CPU1_SA_PAR
  VSS32  = GND
  CA0_B  = M_J_CPU1_SB_CA<0>
  VSS33  = GND
  CA2_B  = M_J_CPU1_SB_CA<2>
  VSS34  = GND
  CA4_B  = M_J_CPU1_SB_CA<4>
  VSS35  = GND
  CA6_B  = M_J_CPU1_SB_CA<6>
  VSS36  = GND
  CS0_B_N  = M_J_CPU1_SB_CS_N<0>
  VSS37  = GND
  \lbd||rsp_a_n\  = M_J_CPU1_SA_RSP<0>
  \lbs||rsp_b_n\  = M_J_CPU1_SB_RSP<0>
  VSS38  = GND
  CB4_B  = M_J_CPU1_SB_CB<4>
  VSS39  = GND
  CB5_B  = M_J_CPU1_SB_CB<5>
  VSS40  = GND
  \dqs9_b_t||tdqs9_b_t||dbi4_b_n\  = M_J_CPU1_SB_DQS_DP<9>
  \dqs9_b_c||tdqs9_b_c\  = M_J_CPU1_SB_DQS_DN<9>
  VSS41  = GND
  CB0_B  = M_J_CPU1_SB_CB<0>
  VSS42  = GND
  CB1_B  = M_J_CPU1_SB_CB<1>
  VSS43  = GND
  DQ0_B  = M_J_CPU1_SB_DQ<0>
  VSS44  = GND
  DQ1_B  = M_J_CPU1_SB_DQ<1>
  VSS45  = GND
  DQS0_B_T  = M_J_CPU1_SB_DQS_DP<0>
  DQS0_B_C  = M_J_CPU1_SB_DQS_DN<0>
  VSS46  = GND
  DQ4_B  = M_J_CPU1_SB_DQ<4>
  VSS47  = GND
  DQ5_B  = M_J_CPU1_SB_DQ<5>
  VSS48  = GND
  DQ8_B  = M_J_CPU1_SB_DQ<8>
  VSS49  = GND
  DQ9_B  = M_J_CPU1_SB_DQ<9>
  VSS50  = GND
  DQS1_B_T  = M_J_CPU1_SB_DQS_DP<1>
  DQS1_B_C  = M_J_CPU1_SB_DQS_DN<1>
  VSS51  = GND
  DQ12_B  = M_J_CPU1_SB_DQ<12>
  VSS52  = GND
  DQ13_B  = M_J_CPU1_SB_DQ<13>
  VSS53  = GND
  DQ16_B  = M_J_CPU1_SB_DQ<16>
  VSS54  = GND
  DQ17_B  = M_J_CPU1_SB_DQ<17>
  VSS55  = GND
  DQS2_B_T  = M_J_CPU1_SB_DQS_DP<2>
  DQS2_B_C  = M_J_CPU1_SB_DQS_DN<2>
  VSS56  = GND
  DQ20_B  = M_J_CPU1_SB_DQ<20>
  VSS57  = GND
  DQ21_B  = M_J_CPU1_SB_DQ<21>
  VSS58  = GND
  DQ24_B  = M_J_CPU1_SB_DQ<24>
  VSS59  = GND
  DQ25_B  = M_J_CPU1_SB_DQ<25>
  VSS60  = GND
  DQS3_B_T  = M_J_CPU1_SB_DQS_DP<3>
  DQS3_B_C  = M_J_CPU1_SB_DQS_DN<3>
  VSS61  = GND
  DQ28_B  = M_J_CPU1_SB_DQ<28>
  VSS62  = GND
  DQ29_B  = M_J_CPU1_SB_DQ<29>
  VSS63  = GND
  RFU1  = NC
  VIN_BULK1  = P12V_MEM_CPU1
  VIN_BULK2  = P12V_MEM_CPU1
  \pwr_good||fail_n\  = PWRGD_CHJ_CPU1_DIMM
  HAS  = PD_CHJ_CPU1_DIMM_SAA
  RFU2  = NC
  RFU3  = NC
  VSS64  = GND
  DQ2_A  = M_J_CPU1_SA_DQ<2>
  VSS65  = GND
  DQ3_A  = M_J_CPU1_SA_DQ<3>
  VSS66  = GND
  \dqs5_a_c||tdqs5_a_c||dqs5_a_t||tdqs5_a_t\  = M_J_CPU1_SA_DQS_DN<5>
  \dqs5_a_t||tdqs5_a_t\  = M_J_CPU1_SA_DQS_DP<5>
  VSS67  = GND
  DQ6_A  = M_J_CPU1_SA_DQ<6>
  VSS68  = GND
  DQ7_A  = M_J_CPU1_SA_DQ<7>
  VSS69  = GND
  DQ10_A  = M_J_CPU1_SA_DQ<10>
  VSS70  = GND
  DQ11_A  = M_J_CPU1_SA_DQ<11>
  VSS71  = GND
  \dqs6_a_c||tdqs6_a_c||dqs6_a_t||tdqs6_a_t\  = M_J_CPU1_SA_DQS_DN<6>
  \dqs6_a_t||tdqs6_a_t\  = M_J_CPU1_SA_DQS_DP<6>
  VSS72  = GND
  DQ14_A  = M_J_CPU1_SA_DQ<14>
  VSS73  = GND
  DQ15_A  = M_J_CPU1_SA_DQ<15>
  VSS74  = GND
  DQ18_A  = M_J_CPU1_SA_DQ<18>
  VSS75  = GND
  DQ19_A  = M_J_CPU1_SA_DQ<19>
  VSS76  = GND
  \dqs7_a_c||tdqs7_a_c\  = M_J_CPU1_SA_DQS_DN<7>
  \dqs7_a_t||tdqs7_a_t\  = M_J_CPU1_SA_DQS_DP<7>
  VSS77  = GND
  DQ22_A  = M_J_CPU1_SA_DQ<22>
  VSS78  = GND
  DQ23_A  = M_J_CPU1_SA_DQ<23>
  VSS79  = GND
  DQ26_A  = M_J_CPU1_SA_DQ<26>
  VSS80  = GND
  DQ27_A  = M_J_CPU1_SA_DQ<27>
  VSS81  = GND
  \dqs8_a_c||tdqs8_a_c\  = M_J_CPU1_SA_DQS_DN<8>
  \dqs8_a_t||tdqs8_a_t\  = M_J_CPU1_SA_DQS_DP<8>
  VSS82  = GND
  DQ30_A  = M_J_CPU1_SA_DQ<30>
  VSS83  = GND
  DQ31_A  = M_J_CPU1_SA_DQ<31>
  VSS84  = GND
  CB2_A  = M_J_CPU1_SA_CB<2>
  VSS85  = GND
  CB3_A  = M_J_CPU1_SA_CB<3>
  VSS86  = GND
  \dqs9_a_c||tdqs9_a_c\  = M_J_CPU1_SA_DQS_DN<9>
  \dqs9_a_t||tdqs9_a_t\  = M_J_CPU1_SA_DQS_DP<9>
  VSS87  = GND
  CB6_A  = M_J_CPU1_SA_CB<6>
  VSS88  = GND
  CB7_A  = M_J_CPU1_SA_CB<7>
  VSS89  = GND
  RESET_N  = M_J_CPU1_RESET_N
  VSS90  = GND
  CS1_A_N  = M_J_CPU1_SA_CS_N<1>
  VSS91  = GND
  CA1_A  = M_J_CPU1_SA_CA<1>
  VSS92  = GND
  CA3_A  = M_J_CPU1_SA_CA<3>
  VSS93  = GND
  CA5_A  = M_J_CPU1_SA_CA<5>
  VSS94  = GND
  CK_T  = M_J_CPU1_CLK_DP<0>
  CK_C  = M_J_CPU1_CLK_DN<0>
  VSS95  = GND
  RFU4  = NC
  CA1_B  = M_J_CPU1_SB_CA<1>
  VSS96  = GND
  CA3_B  = M_J_CPU1_SB_CA<3>
  VSS97  = GND
  CA5_B  = M_J_CPU1_SB_CA<5>
  VSS98  = GND
  PAR_B  = M_J_CPU1_SB_PAR
  VSS99  = GND
  CS1_B_N  = M_J_CPU1_SB_CS_N<1>
  VSS100  = GND
  RFU5  = NC
  RFU6  = NC
  VSS101  = GND
  CB6_B  = M_J_CPU1_SB_CB<6>
  VSS102  = GND
  CB7_B  = M_J_CPU1_SB_CB<7>
  VSS103  = GND
  DQS4_B_C  = M_J_CPU1_SB_DQS_DN<4>
  DQS4_B_T  = M_J_CPU1_SB_DQS_DP<4>
  VSS104  = GND
  CB2_B  = M_J_CPU1_SB_CB<2>
  VSS105  = GND
  CB3_B  = M_J_CPU1_SB_CB<3>
  VSS106  = GND
  DQ2_B  = M_J_CPU1_SB_DQ<2>
  VSS107  = GND
  DQ3_B  = M_J_CPU1_SB_DQ<3>
  VSS108  = GND
  \dqs5_b_c||tdqs5_b_c\  = M_J_CPU1_SB_DQS_DN<5>
  \dqs5_b_t||tdqs5_b_t\  = M_J_CPU1_SB_DQS_DP<5>
  VSS109  = GND
  DQ6_B  = M_J_CPU1_SB_DQ<6>
  VSS110  = GND
  DQ7_B  = M_J_CPU1_SB_DQ<7>
  VSS111  = GND
  DQ10_B  = M_J_CPU1_SB_DQ<10>
  VSS112  = GND
  DQ11_B  = M_J_CPU1_SB_DQ<11>
  VSS113  = GND
  \dqs6_b_c||tdqs6_b_c\  = M_J_CPU1_SB_DQS_DN<6>
  \dqs6_b_t||tdqs6_b_t\  = M_J_CPU1_SB_DQS_DP<6>
  VSS114  = GND
  DQ14_B  = M_J_CPU1_SB_DQ<14>
  VSS115  = GND
  DQ15_B  = M_J_CPU1_SB_DQ<15>
  VSS116  = GND
  DQ18_B  = M_J_CPU1_SB_DQ<18>
  VSS117  = GND
  DQ19_B  = M_J_CPU1_SB_DQ<19>
  VSS118  = GND
  \dqs7_b_c||tdqs7_b_c\  = M_J_CPU1_SB_DQS_DN<7>
  \dqs7_b_t||tdqs7_b_t\  = M_J_CPU1_SB_DQS_DP<7>
  VSS119  = GND
  DQ22_B  = M_J_CPU1_SB_DQ<22>
  VSS120  = GND
  DQ23_B  = M_J_CPU1_SB_DQ<23>
  VSS121  = GND
  DQ26_B  = M_J_CPU1_SB_DQ<26>
  VSS122  = GND
  DQ27_B  = M_J_CPU1_SB_DQ<27>
  VSS123  = GND
  \dqs8_b_c||tdqs8_b_c\  = M_J_CPU1_SB_DQS_DN<8>
  \dqs8_b_t||tdqs8_b_t\  = M_J_CPU1_SB_DQS_DP<8>
  VSS124  = GND
  DQ30_B  = M_J_CPU1_SB_DQ<30>
  VSS125  = GND
  DQ31_B  = M_J_CPU1_SB_DQ<31>
  VSS126  = GND
  G1  = GND
  G2  = GND
  G3  = GND

(kicad_pcb
	(version 20260206)
	(generator "pcbnew")
	(generator_version "10.0")
	(general
		(thickness 1.6)
		(legacy_teardrops no)
	)
	(paper "A4")
	(title_block
		(title "04192023_DAF0TMB3IC0_F0TG_MB_C_brd_V02_OCP.brd")
		(comment 1 "Grand Teton / footprint 1456 of 8354 (J29), pads 92-137 of 291")
	)
	(layers
		(0 "F.Cu" signal "TOP")
		(4 "In1.Cu" signal "GND")
		(6 "In2.Cu" signal "IN1")
		(8 "In3.Cu" signal "GND1")
		(10 "In4.Cu" signal "IN2")
		(12 "In5.Cu" signal "GND2")
		(14 "In6.Cu" signal "IN3")
		(16 "In7.Cu" signal "GND3")
		(18 "In8.Cu" signal "VCC")
		(20 "In9.Cu" signal "VCC1")
		(22 "In10.Cu" signal "GND4")
		(24 "In11.Cu" signal "IN4")
		(26 "In12.Cu" signal "GND5")
		(28 "In13.Cu" signal "IN5")
		(30 "In14.Cu" signal "GND6")
		(32 "In15.Cu" signal "IN6")
		(34 "In16.Cu" signal "GND7")
		(2 "B.Cu" signal "BOTTOM")
		(9 "F.Adhes" user "F.Adhesive")
		(11 "B.Adhes" user "B.Adhesive")
		(13 "F.Paste" user "Package Geometry/Pastemask Top")
		(15 "B.Paste" user "Package Geometry/Pastemask Bottom")
		(5 "F.SilkS" user "Ref Des/Silkscreen Top")
		(7 "B.SilkS" user "Ref Des/Silkscreen Bottom")
		(1 "F.Mask" user "Board Geometry/Soldermask Top")
		(3 "B.Mask" user "Board Geometry/Soldermask Bottom")
		(17 "Dwgs.User" user "User.Drawings")
		(19 "Cmts.User" user "User.Comments")
		(21 "Eco1.User" user "User.Eco1")
		(23 "Eco2.User" user "User.Eco2")
		(25 "Edge.Cuts" user "Board Geometry/Outline")
		(27 "Margin" user)
		(31 "F.CrtYd" user "Package Geometry/Place Bound Top")
		(29 "B.CrtYd" user "Package Geometry/Place Bound Bottom")
		(35 "F.Fab" user "Ref Des/Assembly Top")
		(33 "B.Fab" user "Ref Des/Assembly Bottom")
	)
	(footprint ""
		(layer "F.Cu")
		(at 189.110112 -255.560322 180)
		(property "Reference" "J29"
			(at -2.7178 -81.857088 0)
			(unlocked yes)
			(layer "F.SilkS")
			(effects
				(font
					(size 0.7874 0.5842)
					(thickness 0.1524)
				)
			)
		)
		(property "Value" ""
			(at 0 0 180)
			(layer "F.Fab")
			(effects
				(font
					(size 1.27 1.27)
				)
			)
		)
		(duplicate_pad_numbers_are_jumpers no)
		(pad "92" smd rect
			(at -2.050034 19.12493 90)
			(size 0.519938 1.4986)
			(layers "F.Cu" "F.Mask" "F.Paste")
			(net "GND")
		)
		(pad "93" smd rect
			(at -2.050034 19.975068 90)
			(size 0.519938 1.4986)
			(layers "F.Cu" "F.Mask" "F.Paste")
			(net "M_J_CPU1_SB_DQS_DP<9>")
		)
		(pad "94" smd rect
			(at -2.050034 20.824952 90)
			(size 0.519938 1.4986)
			(layers "F.Cu" "F.Mask" "F.Paste")
			(net "M_J_CPU1_SB_DQS_DN<9>")
		)
		(pad "95" smd rect
			(at -2.050034 21.67509 90)
			(size 0.519938 1.4986)
			(layers "F.Cu" "F.Mask" "F.Paste")
			(net "GND")
		)
		(pad "96" smd rect
			(at -2.050034 22.524974 90)
			(size 0.519938 1.4986)
			(layers "F.Cu" "F.Mask" "F.Paste")
			(net "M_J_CPU1_SB_CB<0>")
		)
		(pad "97" smd rect
			(at -2.050034 23.375112 90)
			(size 0.519938 1.4986)
			(layers "F.Cu" "F.Mask" "F.Paste")
			(net "GND")
		)
		(pad "98" smd rect
			(at -2.050034 24.224996 90)
			(size 0.519938 1.4986)
			(layers "F.Cu" "F.Mask" "F.Paste")
			(net "M_J_CPU1_SB_CB<1>")
		)
		(pad "99" smd rect
			(at -2.050034 25.07488 90)
			(size 0.519938 1.4986)
			(layers "F.Cu" "F.Mask" "F.Paste")
			(net "GND")
		)
		(pad "100" smd rect
			(at -2.050034 25.925018 90)
			(size 0.519938 1.4986)
			(layers "F.Cu" "F.Mask" "F.Paste")
			(net "M_J_CPU1_SB_DQ<0>")
		)
		(pad "101" smd rect
			(at -2.050034 26.774902 90)
			(size 0.519938 1.4986)
			(layers "F.Cu" "F.Mask" "F.Paste")
			(net "GND")
		)
		(pad "102" smd rect
			(at -2.050034 27.62504 90)
			(size 0.519938 1.4986)
			(layers "F.Cu" "F.Mask" "F.Paste")
			(net "M_J_CPU1_SB_DQ<1>")
		)
		(pad "103" smd rect
			(at -2.050034 28.474924 90)
			(size 0.519938 1.4986)
			(layers "F.Cu" "F.Mask" "F.Paste")
			(net "GND")
		)
		(pad "104" smd rect
			(at -2.050034 29.325062 90)
			(size 0.519938 1.4986)
			(layers "F.Cu" "F.Mask" "F.Paste")
			(net "M_J_CPU1_SB_DQS_DP<0>")
		)
		(pad "105" smd rect
			(at -2.050034 30.174946 90)
			(size 0.519938 1.4986)
			(layers "F.Cu" "F.Mask" "F.Paste")
			(net "M_J_CPU1_SB_DQS_DN<0>")
		)
		(pad "106" smd rect
			(at -2.050034 31.025084 90)
			(size 0.519938 1.4986)
			(layers "F.Cu" "F.Mask" "F.Paste")
			(net "GND")
		)
		(pad "107" smd rect
			(at -2.050034 31.874968 90)
			(size 0.519938 1.4986)
			(layers "F.Cu" "F.Mask" "F.Paste")
			(net "M_J_CPU1_SB_DQ<4>")
		)
		(pad "108" smd rect
			(at -2.050034 32.725106 90)
			(size 0.519938 1.4986)
			(layers "F.Cu" "F.Mask" "F.Paste")
			(net "GND")
		)
		(pad "109" smd rect
			(at -2.050034 33.57499 90)
			(size 0.519938 1.4986)
			(layers "F.Cu" "F.Mask" "F.Paste")
			(net "M_J_CPU1_SB_DQ<5>")
		)
		(pad "110" smd rect
			(at -2.050034 34.425128 90)
			(size 0.519938 1.4986)
			(layers "F.Cu" "F.Mask" "F.Paste")
			(net "GND")
		)
		(pad "111" smd rect
			(at -2.050034 35.275012 90)
			(size 0.519938 1.4986)
			(layers "F.Cu" "F.Mask" "F.Paste")
			(net "M_J_CPU1_SB_DQ<8>")
		)
		(pad "112" smd rect
			(at -2.050034 36.124896 90)
			(size 0.519938 1.4986)
			(layers "F.Cu" "F.Mask" "F.Paste")
			(net "GND")
		)
		(pad "113" smd rect
			(at -2.050034 36.975034 90)
			(size 0.519938 1.4986)
			(layers "F.Cu" "F.Mask" "F.Paste")
			(net "M_J_CPU1_SB_DQ<9>")
		)
		(pad "114" smd rect
			(at -2.050034 37.824918 90)
			(size 0.519938 1.4986)
			(layers "F.Cu" "F.Mask" "F.Paste")
			(net "GND")
		)
		(pad "115" smd rect
			(at -2.050034 38.675056 90)
			(size 0.519938 1.4986)
			(layers "F.Cu" "F.Mask" "F.Paste")
			(net "M_J_CPU1_SB_DQS_DP<1>")
		)
		(pad "116" smd rect
			(at -2.050034 39.52494 90)
			(size 0.519938 1.4986)
			(layers "F.Cu" "F.Mask" "F.Paste")
			(net "M_J_CPU1_SB_DQS_DN<1>")
		)
		(pad "117" smd rect
			(at -2.050034 40.375078 90)
			(size 0.519938 1.4986)
			(layers "F.Cu" "F.Mask" "F.Paste")
			(net "GND")
		)
		(pad "118" smd rect
			(at -2.050034 41.224962 90)
			(size 0.519938 1.4986)
			(layers "F.Cu" "F.Mask" "F.Paste")
			(net "M_J_CPU1_SB_DQ<12>")
		)
		(pad "119" smd rect
			(at -2.050034 42.0751 90)
			(size 0.519938 1.4986)
			(layers "F.Cu" "F.Mask" "F.Paste")
			(net "GND")
		)
		(pad "120" smd rect
			(at -2.050034 42.924984 90)
			(size 0.519938 1.4986)
			(layers "F.Cu" "F.Mask" "F.Paste")
			(net "M_J_CPU1_SB_DQ<13>")
		)
		(pad "121" smd rect
			(at -2.050034 43.775122 90)
			(size 0.519938 1.4986)
			(layers "F.Cu" "F.Mask" "F.Paste")
			(net "GND")
		)
		(pad "122" smd rect
			(at -2.050034 44.625006 90)
			(size 0.519938 1.4986)
			(layers "F.Cu" "F.Mask" "F.Paste")
			(net "M_J_CPU1_SB_DQ<16>")
		)
		(pad "123" smd rect
			(at -2.050034 45.47489 90)
			(size 0.519938 1.4986)
			(layers "F.Cu" "F.Mask" "F.Paste")
			(net "GND")
		)
		(pad "124" smd rect
			(at -2.050034 46.325028 90)
			(size 0.519938 1.4986)
			(layers "F.Cu" "F.Mask" "F.Paste")
			(net "M_J_CPU1_SB_DQ<17>")
		)
		(pad "125" smd rect
			(at -2.050034 47.174912 90)
			(size 0.519938 1.4986)
			(layers "F.Cu" "F.Mask" "F.Paste")
			(net "GND")
		)
		(pad "126" smd rect
			(at -2.050034 48.02505 90)
			(size 0.519938 1.4986)
			(layers "F.Cu" "F.Mask" "F.Paste")
			(net "M_J_CPU1_SB_DQS_DP<2>")
		)
		(pad "127" smd rect
			(at -2.050034 48.874934 90)
			(size 0.519938 1.4986)
			(layers "F.Cu" "F.Mask" "F.Paste")
			(net "M_J_CPU1_SB_DQS_DN<2>")
		)
		(pad "128" smd rect
			(at -2.050034 49.725072 90)
			(size 0.519938 1.4986)
			(layers "F.Cu" "F.Mask" "F.Paste")
			(net "GND")
		)
		(pad "129" smd rect
			(at -2.050034 50.574956 90)
			(size 0.519938 1.4986)
			(layers "F.Cu" "F.Mask" "F.Paste")
			(net "M_J_CPU1_SB_DQ<20>")
		)
		(pad "130" smd rect
			(at -2.050034 51.425094 90)
			(size 0.519938 1.4986)
			(layers "F.Cu" "F.Mask" "F.Paste")
			(net "GND")
		)
		(pad "131" smd rect
			(at -2.050034 52.274978 90)
			(size 0.519938 1.4986)
			(layers "F.Cu" "F.Mask" "F.Paste")
			(net "M_J_CPU1_SB_DQ<21>")
		)
		(pad "132" smd rect
			(at -2.050034 53.125116 90)
			(size 0.519938 1.4986)
			(layers "F.Cu" "F.Mask" "F.Paste")
			(net "GND")
		)
		(pad "133" smd rect
			(at -2.050034 53.975 90)
			(size 0.519938 1.4986)
			(layers "F.Cu" "F.Mask" "F.Paste")
			(net "M_J_CPU1_SB_DQ<24>")
		)
		(pad "134" smd rect
			(at -2.050034 54.824884 90)
			(size 0.519938 1.4986)
			(layers "F.Cu" "F.Mask" "F.Paste")
			(net "GND")
		)
		(pad "135" smd rect
			(at -2.050034 55.675022 90)
			(size 0.519938 1.4986)
			(layers "F.Cu" "F.Mask" "F.Paste")
			(net "M_J_CPU1_SB_DQ<25>")
		)
		(pad "136" smd rect
			(at -2.050034 56.524906 90)
			(size 0.519938 1.4986)
			(layers "F.Cu" "F.Mask" "F.Paste")
			(net "GND")
		)
		(pad "137" smd rect
			(at -2.050034 57.375044 90)
			(size 0.519938 1.4986)
			(layers "F.Cu" "F.Mask" "F.Paste")
			(net "M_J_CPU1_SB_DQS_DP<3>")
		)
	)
)
